# SCM (Grand Teton) — schematic netlist excerpt (pin names and nets, part order shuffled) for the footprints in the layout excerpt that follows; sources: Cadence DE-HDL packaged netlist, KiCad conversion of 12092022_DA0F0TMDCD0_F0T_Management_Board_D_brd_V3_OCP.brd

R126  Q_RES  10K 1% CHIP  pkg 0402LF  page 46 : A = SMB_PCH_TPM_SDA ; B = P3V3_AUX
R868  Q_RES  0 5% EMPTY  pkg 0402LF  page 51 : A = PWRGD_P5V_AUX_R ; B = EN_P3V3_R1

(kicad_pcb
	(version 20260206)
	(generator "pcbnew")
	(generator_version "10.0")
	(general
		(thickness 1.6)
		(legacy_teardrops no)
	)
	(paper "A4")
	(title_block
		(title "12092022_DA0F0TMDCD0_F0T_Management_Board_D_brd_V3_OCP.brd")
		(comment 1 "Grand Teton / footprints 13-14 of 1440")
	)
	(layers
		(0 "F.Cu" signal "TOP")
		(4 "In1.Cu" signal "GND")
		(6 "In2.Cu" signal "IN1")
		(8 "In3.Cu" signal "GND1")
		(10 "In4.Cu" signal "IN2")
		(12 "In5.Cu" signal "VCC")
		(14 "In6.Cu" signal "VCC1")
		(16 "In7.Cu" signal "IN3")
		(18 "In8.Cu" signal "GND2")
		(20 "In9.Cu" signal "IN4")
		(22 "In10.Cu" signal "GND3")
		(2 "B.Cu" signal "BOTTOM")
		(9 "F.Adhes" user "F.Adhesive")
		(11 "B.Adhes" user "B.Adhesive")
		(13 "F.Paste" user "Package Geometry/Pastemask Top")
		(15 "B.Paste" user "Package Geometry/Pastemask Bottom")
		(5 "F.SilkS" user "Ref Des/Silkscreen Top")
		(7 "B.SilkS" user "Ref Des/Silkscreen Bottom")
		(1 "F.Mask" user "Board Geometry/Soldermask Top")
		(3 "B.Mask" user "Board Geometry/Soldermask Bottom")
		(17 "Dwgs.User" user "User.Drawings")
		(19 "Cmts.User" user "User.Comments")
		(21 "Eco1.User" user "User.Eco1")
		(23 "Eco2.User" user "User.Eco2")
		(25 "Edge.Cuts" user "Board Geometry/Outline")
		(27 "Margin" user)
		(31 "F.CrtYd" user "Package Geometry/Place Bound Top")
		(29 "B.CrtYd" user "Package Geometry/Place Bound Bottom")
		(35 "F.Fab" user "Ref Des/Assembly Top")
		(33 "B.Fab" user "Ref Des/Assembly Bottom")
	)
	(footprint ""
		(layer "F.Cu")
		(at 68.961 -101.473)
		(property "Reference" "R126"
			(at 0 0 0)
			(layer "F.SilkS")
			(hide yes)
			(effects
				(font
					(size 1.27 1.27)
				)
			)
		)
		(property "Value" ""
			(at 0 0 0)
			(layer "F.Fab")
			(effects
				(font
					(size 1.27 1.27)
				)
			)
		)
		(duplicate_pad_numbers_are_jumpers no)
		(fp_line
			(start -0.7874 -0.4064)
			(end 0.7874 -0.4064)
			(stroke
				(width 0.1524)
				(type default)
			)
			(layer "F.SilkS")
		)
		(fp_line
			(start -0.7874 0.4064)
			(end -0.7874 -0.4064)
			(stroke
				(width 0.1524)
				(type default)
			)
			(layer "F.SilkS")
		)
		(fp_line
			(start 0.7874 -0.4064)
			(end 0.7874 0.4064)
			(stroke
				(width 0.1524)
				(type default)
			)
			(layer "F.SilkS")
		)
		(fp_line
			(start 0.7874 0.4064)
			(end -0.7874 0.4064)
			(stroke
				(width 0.1524)
				(type default)
			)
			(layer "F.SilkS")
		)
		(fp_line
			(start -0.67945 -0.305054)
			(end -0.12065 -0.305054)
			(stroke
				(width 0.1)
				(type default)
			)
			(layer "F.Fab")
		)
		(fp_line
			(start -0.67945 0.3048)
			(end -0.67945 -0.305054)
			(stroke
				(width 0.1)
				(type default)
			)
			(layer "F.Fab")
		)
		(fp_line
			(start -0.12065 -0.305054)
			(end -0.12065 -0.2794)
			(stroke
				(width 0.1)
				(type default)
			)
			(layer "F.Fab")
		)
		(fp_line
			(start -0.12065 -0.2794)
			(end 0.12065 -0.2794)
			(stroke
				(width 0.1)
				(type default)
			)
			(layer "F.Fab")
		)
		(fp_line
			(start -0.12065 0.2794)
			(end -0.12065 0.3048)
			(stroke
				(width 0.1)
				(type default)
			)
			(layer "F.Fab")
		)
		(fp_line
			(start -0.12065 0.3048)
			(end -0.67945 0.3048)
			(stroke
				(width 0.1)
				(type default)
			)
			(layer "F.Fab")
		)
		(fp_line
			(start 0.120396 0.2794)
			(end -0.12065 0.2794)
			(stroke
				(width 0.1)
				(type default)
			)
			(layer "F.Fab")
		)
		(fp_line
			(start 0.120396 0.3048)
			(end 0.120396 0.2794)
			(stroke
				(width 0.1)
				(type default)
			)
			(layer "F.Fab")
		)
		(fp_line
			(start 0.12065 -0.3048)
			(end 0.67945 -0.3048)
			(stroke
				(width 0.1)
				(type default)
			)
			(layer "F.Fab")
		)
		(fp_line
			(start 0.12065 -0.2794)
			(end 0.12065 -0.3048)
			(stroke
				(width 0.1)
				(type default)
			)
			(layer "F.Fab")
		)
		(fp_line
			(start 0.67945 -0.3048)
			(end 0.67945 0.3048)
			(stroke
				(width 0.1)
				(type default)
			)
			(layer "F.Fab")
		)
		(fp_line
			(start 0.67945 0.3048)
			(end 0.120396 0.3048)
			(stroke
				(width 0.1)
				(type default)
			)
			(layer "F.Fab")
		)
		(pad "1" smd circle
			(at -0.40005 0)
			(size 0 0)
			(layers "F.Cu" "F.Mask" "F.Paste")
			(net "SMB_PCH_TPM_SDA")
		)
		(pad "2" smd circle
			(at 0.40005 0)
			(size 0 0)
			(layers "F.Cu" "F.Mask" "F.Paste")
			(net "P3V3_AUX")
		)
	)
	(footprint ""
		(layer "F.Cu")
		(at 8.9662 -54.5338 180)
		(property "Reference" "R868"
			(at 0 0 180)
			(layer "F.SilkS")
			(hide yes)
			(effects
				(font
					(size 1.27 1.27)
				)
			)
		)
		(property "Value" ""
			(at 0 0 180)
			(layer "F.Fab")
			(effects
				(font
					(size 1.27 1.27)
				)
			)
		)
		(duplicate_pad_numbers_are_jumpers no)
		(fp_line
			(start 0.7874 0.4064)
			(end -0.7874 0.4064)
			(stroke
				(width 0.1524)
				(type default)
			)
			(layer "F.SilkS")
		)
		(fp_line
			(start 0.7874 -0.4064)
			(end 0.7874 0.4064)
			(stroke
				(width 0.1524)
				(type default)
			)
			(layer "F.SilkS")
		)
		(fp_line
			(start -0.7874 0.4064)
			(end -0.7874 -0.4064)
			(stroke
				(width 0.1524)
				(type default)
			)
			(layer "F.SilkS")
		)
		(fp_line
			(start -0.7874 -0.4064)
			(end 0.7874 -0.4064)
			(stroke
				(width 0.1524)
				(type default)
			)
			(layer "F.SilkS")
		)
		(fp_line
			(start 0.67945 0.3048)
			(end 0.120396 0.3048)
			(stroke
				(width 0.1)
				(type default)
			)
			(layer "F.Fab")
		)
		(fp_line
			(start 0.67945 -0.3048)
			(end 0.67945 0.3048)
			(stroke
				(width 0.1)
				(type default)
			)
			(layer "F.Fab")
		)
		(fp_line
			(start 0.12065 -0.2794)
			(end 0.12065 -0.3048)
			(stroke
				(width 0.1)
				(type default)
			)
			(layer "F.Fab")
		)
		(fp_line
			(start 0.12065 -0.3048)
			(end 0.67945 -0.3048)
			(stroke
				(width 0.1)
				(type default)
			)
			(layer "F.Fab")
		)
		(fp_line
			(start 0.120396 0.3048)
			(end 0.120396 0.2794)
			(stroke
				(width 0.1)
				(type default)
			)
			(layer "F.Fab")
		)
		(fp_line
			(start 0.120396 0.2794)
			(end -0.12065 0.2794)
			(stroke
				(width 0.1)
				(type default)
			)
			(layer "F.Fab")
		)
		(fp_line
			(start -0.12065 0.3048)
			(end -0.67945 0.3048)
			(stroke
				(width 0.1)
				(type default)
			)
			(layer "F.Fab")
		)
		(fp_line
			(start -0.12065 0.2794)
			(end -0.12065 0.3048)
			(stroke
				(width 0.1)
				(type default)
			)
			(layer "F.Fab")
		)
		(fp_line
			(start -0.12065 -0.2794)
			(end 0.12065 -0.2794)
			(stroke
				(width 0.1)
				(type default)
			)
			(layer "F.Fab")
		)
		(fp_line
			(start -0.12065 -0.305054)
			(end -0.12065 -0.2794)
			(stroke
				(width 0.1)
				(type default)
			)
			(layer "F.Fab")
		)
		(fp_line
			(start -0.67945 0.3048)
			(end -0.67945 -0.305054)
			(stroke
				(width 0.1)
				(type default)
			)
			(layer "F.Fab")
		)
		(fp_line
			(start -0.67945 -0.305054)
			(end -0.12065 -0.305054)
			(stroke
				(width 0.1)
				(type default)
			)
			(layer "F.Fab")
		)
		(pad "1" smd circle
			(at -0.40005 0 180)
			(size 0 0)
			(layers "F.Cu" "F.Mask" "F.Paste")
			(net "PWRGD_P5V_AUX_R")
		)
		(pad "2" smd circle
			(at 0.40005 0 180)
			(size 0 0)
			(layers "F.Cu" "F.Mask" "F.Paste")
			(net "EN_P3V3_R1")
		)
	)
)
